                    - SPARES  LIST -

MOSFET_NCH_DUAL-PJT138K,SMLF,IA
     Q13  2
      Q9  2

                    - PART SUMMARY -

2N7002A7-2N7002A-7,SMLF,IC,BAMA	BAM70020068	3
74HC1G126GW-74HC1G126GW,SMLF,IA	AL1G0126007	4
74LVC1G07GW-74LVC1G07GW,SMLF,EA	ALVC1G07002	1
74LVC1G07GW-74LVC1G07GW,SMLF,IA	ALVC1G07002	2
74LVC1G07W57-74LVC1G07W5-7,SMLA	ALVC1G07001	1
74LVC1G08GW_SM-74LVC1G08GW,IC,A	ALVC1G08009	4
74LVC1G126SE7-74LVC1G126SE-7,SA	AL1G0126009	1
74LVC1G17GW-74LVC1G17GW,SMLF,IA	AL1G0017K01	1
74LVC1G66GV-74LVC1G66GV,SMLF,IA	AL001G66000	1
74LVC1G74DP-74LVC1G74DP,SMLF,IA	AL1G0074K01	1
74LVC2G07DW7-74LVC2G07DW-7,SMLA	AL002G07003	3
AP2205W57-AP2205-W5-7,SMLF,IC,A	AL002205001	1
AP22811AW57-AP22811AW5-7,SMLF,A	AL022811000	1
AST2600A3GP-AST2600A3-GP,SMLF,A	AJ026000T06	1
BAS70057F-BAS70-05-7-F,SMLF,ICA	BC0BAS70Z01	1
BAT54C-BAT54C,SMLF,IC,BCBAT54CA	BCBAT54CZ04	1
BZA462A-BZA462A,SMLF,EMPTY,BCZA	BCZA462AZ01	1
CONN8_210HP1080BR1-CONN8_210-HA	DFHD08MS392	1
CONN8_TSW10407FD-CONN8_TSW-104A	DFHD08MS225	1
CONN9_GSB3111315HR-CONN9_GSB31A	DFHS09FR401	1
DIODE_BIDIRECTIONAL-UCLAMP0511A	BC00511TZ00	1
DT1240E04LP7-DT1240E-04LP-7,SMA	BC001240Z01	3
DUMMY_SYMBOL-BIOS_FLASH,MECH,MA	DUMMY9	1
DUMMY_SYMBOL-BMC_FLASH,MECH,EMA	DUMMY8	2
FCONN168_ME1016810202011_SCM-FA	GOLD244	1
FSA3357K8X-FSA3357K8X,SMLF,IC,A	AL003357009	2
HOLE_TH-EMPTY,DUMMY50	DUMMY50	2
HOLE_TH-EMPTY,HOLE1211	HOLE1211	2
HOLE_TH-EMPTY,HOLE1247	HOLE1247	1
HOLE_TH-EMPTY,HOLE1248	HOLE1248	1
HOLE_TH-EMPTY,HOLE620	HOLE620	2
HOLE_TH-EMPTY,TMP-C_HOLE8	TMP-C_HOLE8	2
IDTQS3VH257PAG_SMLF-IDTQS3VH25A	AL000257K00	2
K4A8G165WCBCTD-K4A8G165WC-BCTDA	AKD5FGUT502	1
LCMXO3LF2100C5BG256C-LCMXO3LF-A	AJ021000T03	1
M24128BWDW6TP-M24128-BWDW6TP,SA	AKE30Z0K610	1
MC74VHC1G07DFT2G-MC74VHC1G07DFA	AL001G07003	1
MC74VHC1G32DTT1G-MC74VHC1G32DTA	AL001G32031	4
ME_DUMMY_SYMBOL-PB-E1_SMALL,MEA	DUMMY3	1
ME_DUMMY_SYMBOL-QUANTA_LOGO_7XA	DUMMY1	1
ME_DUMMY_SYMBOL-SNLABEL_7X7,MEA	DUMMY69	1
ME_DUMMY_SYMBOL-WEEE,MECH,EMPTA	DUMMY2	1
MMBT39047F-MMBT3904-7-F,SMLF,IA	BA0390400H0	2
MOSFET_DUAL_6P-2N7002KDW,SMLF,A	BAM70020047	1
MOSFET_NCH_4D1S-NTGS4141NT1G,SA	BAM41410005	1
MOSFET_NCH_DUAL-2N7002KDW,SMLFA	BAM70020047	1
MOSFET_NCH_DUAL-PJT138K,SMLF,IA	BAM138K0003	2
MOSFET_N_GSD-DMG6968U-7,SMLF,IA	BAM69680000	1
MOSFET_N_GSD-NX7002AK,SMLF,IC,A	BAM70020062	1
MOSFET_N_SMLF-BSS138K,BSS138K,A	BAM138K0000	1
MOSFET_PCH_GDS-NTR1P02LT1G,SMLA	BAM1P020000	1
MPQ8626GDZ-MPQ8626GD-Z,SMLF,ICA	AL008626000	1
MPQ8633AGLEC807Z-MPQ8633AGLE-CA	AL008633007	1
MX25L51245GMI10G-MX25L51245GMIA	AKE3FF00Z00	1
NB695GDZ-NB695GD-Z,SMLF,IC,AL0A	AL000695001	2
NC7SB3157_SMLF-NC7SB3157P6X,NCA	ALSB3157000	4
NCP380HSNAJAAT1G-NCP380HSNAJAAA	AL000380K00	1
OSC4_7X25000018-25MHZ,SMLF,MISA	BF625000023	2
PCA9517ADP_SMLF-PCA9517ADP,IC,A	AL009517K00	1
PCA9555PW_SMLF-PCA9555PW,IC,TMA	AL009555K04	1
PI3PCIE3212ZBEX-PI3PCIE3212ZBEA	AL003212003	1
PICOPROBE_BXA-DELTA-L 4.0,SMLFA	TP33	16
PRTR5V0U2X-PRTR5V0U2X,SMLF,IC,A	AL5V0U2X000	1
Q_CAP_0402-0.1UF,25V,10%,EMPTYA	CH4104K1B00	7
Q_CAP_0402-0.1UF,25V,10%,X7R,CA	CH4104K1B00	173
Q_CAP_0402-0.22UF,16V,10%,EMPTA	CH4223K1B00	1
Q_CAP_0402-0.22UF,16V,10%,X7R,A	CH4223K1B00	5
Q_CAP_0402-100PF,50V,5%,EMPTY,A	CH11006JB18	2
Q_CAP_0402-100PF,50V,5%,NPO,CHA	CH11006JB00	3
Q_CAP_0402-10PF,50V,1%,NPO,TMPA	CH0106F0B00	2
Q_CAP_0402-15PF,50V,5%,C0G,CH0A	CH01506JB06	3
Q_CAP_0402-18PF,50V,5%,C0G,CH0A	CH01806JB07	1
Q_CAP_0402-1UF,16V,10%,EMPTY,TA	CH5103K9B00	3
Q_CAP_0402-2200PF,50V,10%,X7R,A	CH22206KB16	2
Q_CAP_0402-22PF,50V,5%,NPO,TMPA	CH02206JB08	2
Q_CAP_0402-3300PF,50V,10%,X7R,A	CH2336K1B12	1
Q_CAP_0402-470PF,50V,10%,X7R,TA	CH14706KB18	5
Q_CAP_0603-1UF,16V,10%,EMPTY,TA	CH5103K1900	1
Q_CAP_0805-22UF,4V,20%,X6S,TMPA	CH622KMEA01	8
Q_CAP_C0402-0.001UF,50V,10%,EMA	CH30106KB19	6
Q_CAP_C0402-0.01UF,50V,10%,EMPA	CH31006KB18	6
Q_CAP_C0402-0.01UF,50V,10%,X7RA	CH31006KB18	8
Q_CAP_C0402-10UF,6.3V,20%,X6S,A	CH6101MEB01	6
Q_CAP_C0402-1UF,25V,10%,EMPTY,A	CH5104KEB02	2
Q_CAP_C0402-1UF,25V,10%,X6S,CHA	CH5104KEB02	65
Q_CAP_C0402-2.2UF,10V,10%,X6S,A	CH5222KEB01	1
Q_CAP_C0402-4700P,25V,10%,EMPTA	CH2474K1B08	1
Q_CAP_C0402-68PF,50V,5%,COG,CHA	CH06806JB01	1
Q_CAP_C0603-10UF,16V,20%,X6S,CA	CH6103ME902	2
Q_CAP_C0603-22UF,10V,20%,EMPTYA	CH6222M9901	1
Q_CAP_C0603-22UF,6.3V,20%,X6S,A	CH6221ME900	12
Q_CAP_C0603-4.7UF,25V,10%,X6S,A	CH5474KE906	3
Q_CAP_C0805-10UF,25V,10%,X6S,CA	CH6104KEA00	8
Q_CAP_C0805-22UF,10V,20%,X6S,CA	CH6222MEA00	9
Q_CAP_C0805-22UF,16V,20%,X6S,CA	CH6223MEA01	7
Q_CAP_C1206-47UF,6.3V,20%,X6S,A	CH6471ME200	2
Q_DIODE_SMLF-SDMK0340L-7-F,EMPA	BC000340033	1
Q_DIODE_SMLF-SDMK0340L-7-F,IC,A	BC000340033	1
Q_FUSE_SMLF-1.1A/8V,EMPTY,DK11A	DK110TPU003	1
Q_INDUCTOR4P_12-67/320MA,320MAA	CX21SN67000	3
Q_INDUCTOR_SMLF-1UH,IND,CV-10BA	CV-10B0MZ13	2
Q_INDUCTOR_SMLF-3.3UH/6A,IND,CA	CV-3360MZ07	1
Q_INDUCTOR_SMLF-4.7UH,IND,CV-4A	CV-47A0MZ10	1
Q_INDUCTOR_SMLF-BLM18BB470/500A	CX8BB470007	3
Q_INDUCTOR_SMLF-BLM18EG121SN1DA	CX8EG121000	2
Q_INDUCTOR_SMLF-BLM18PG121SN1DA	CX8PG121009	14
Q_INDUCTOR_SMLF-BLM18PG121SN1DB	CX8PG121009	1
Q_INDUCTOR_SMLF-BLM18SN220TN1DA	CX220TN1001	4
Q_LED_SMLF-LED_BLUE,LTST-C281TA	BEBL0172Z00	2
Q_LED_SMLF-LED_GREEN,19-213/GVA	BEGR0278Z00	5
Q_LED_SMLF-LED_RED,19-217/R6C-A	BERD0034Z07	4
Q_LED_THLF-LED_BLUE,HV-312470/A	BEBL0277D00	4
Q_LED_THLF-LED_YELLOW,LTL-R42FA	BEYL0182D00	1
Q_RES_0402LF-0,5%,1/16W,CHIP,CA	CS00002JB13	154
Q_RES_0402LF-0,5%,1/16W,EMPTY,A	CS00002JB13	35
Q_RES_0402LF-1.69K,1%,1/16W,CHA	CS21692FB04	1
Q_RES_0402LF-1.8K,1%,1/16W,CHIA	CS21802FB10	2
Q_RES_0402LF-10,1%,1/16W,CHIP,A	CS01002FB07	3
Q_RES_0402LF-100,1%,1/16W,CHIPA	CS11002FB07	12
Q_RES_0402LF-100,1%,1/16W,EMPTA	CS11002FB07	7
Q_RES_0402LF-100K,1%,1/16W,CHIA	CS41002FB09	16
Q_RES_0402LF-100K,1%,1/16W,EMPA	CS41002FB09	8
Q_RES_0402LF-10K,1%,1/16W,CHIPA	CS31002FB08	45
Q_RES_0402LF-10K,1%,1/16W,EMPTA	CS31002FB08	7
Q_RES_0402LF-10K,1%,1/16W,EMPTB	CS31002FB26	9
Q_RES_0402LF-110,1%,1/16W,CHIPA	CS11102FB03	4
Q_RES_0402LF-12.4K,1%,1/16W,CHA	CS31242FB02	2
Q_RES_0402LF-120,1%,1/16W,CHIPA	CS11202FB02	48
Q_RES_0402LF-120,1%,1/16W,EMPTA	CS11202FB02	2
Q_RES_0402LF-12K,1%,1/16W,CHIPA	CS31202FB04	2
Q_RES_0402LF-15.8K,1%,1/16W,CHA	CS31582FB02	1
Q_RES_0402LF-150,1%,1/16W,CHIPA	CS11502FB07	7
Q_RES_0402LF-150K,1%,1/16W,CHIA	CS41502FB04	1
Q_RES_0402LF-150K,1%,1/16W,EMPA	CS41502FB04	1
Q_RES_0402LF-15K,1%,1/16W,CHIPA	CS31502FB05	1
Q_RES_0402LF-16.9K,1%,1/16W,CHA	CS31692FB03	1
Q_RES_0402LF-1K,1%,1/16W,CHIP,A	CS21002FB06	21
Q_RES_0402LF-1K,1%,1/16W,EMPTYA	CS21002FB06	9
Q_RES_0402LF-1K,1%,1/16W,EMPTYB	CS21002FB24	4
Q_RES_0402LF-2.2,1%,1/16W,CHIPA	CS-2202FB01	1
Q_RES_0402LF-2.21K,1%,1/16W,EMA	CS22212FB06	2
Q_RES_0402LF-2.2K,5%,1/16W,CHIA	CS22202JB07	21
Q_RES_0402LF-2.74K,1%,1/16W,CHA	CS22742FB05	1
Q_RES_0402LF-2.87K,1%,1/16W,CHA	CS22872FB03	2
Q_RES_0402LF-20.5K,1%,1/16W,CHA	CS32052FB02	1
Q_RES_0402LF-200,1%,1/16W,CHIPA	CS12002FB06	1
Q_RES_0402LF-200K,1%,1/16W,CHIA	CS42002FB05	1
Q_RES_0402LF-20K,1%,1/16W,CHIPA	CS32002FB06	2
Q_RES_0402LF-22,1%,1/16W,CHIP,A	CS02202FB02	13
Q_RES_0402LF-220,1%,1/16W,CHIPA	CS12202FB04	4
Q_RES_0402LF-240,1%,1/16W,CHIPA	CS12402FB01	2
Q_RES_0402LF-25.5K,1%,1/16W,CHA	CS32552FB06	1
Q_RES_0402LF-2K,1%,1/16W,CHIP,A	CS22002FB07	16
Q_RES_0402LF-2K,1%,1/16W,EMPTYA	CS22002FB07	1
Q_RES_0402LF-316,1%,1/16W,CHIPA	CS13162FB01	3
Q_RES_0402LF-33.2,1%,1/16W,CHIA	CS03322FB03	197
Q_RES_0402LF-33.2,1%,1/16W,EMPA	CS03322FB03	19
Q_RES_0402LF-330,1%,1/16W,CHIPA	CS13302FB00	1
Q_RES_0402LF-4.7K,1%,1/16W,CHIA	CS24702FB06	84
Q_RES_0402LF-4.7K,1%,1/16W,EMPA	CS24702FB06	35
Q_RES_0402LF-4.7K,1%,1/16W,EMPB	CS24702FB10	9
Q_RES_0402LF-40.2,1%,1/16W,CHIA	CS04022FB28	1
Q_RES_0402LF-402,1%,1/16W,CHIPA	CS14022FB02	1
Q_RES_0402LF-470K,1%,1/16W,CHIA	CS44702FB02	1
Q_RES_0402LF-47K,1%,1/16W,CHIPA	CS34702FB01	3
Q_RES_0402LF-49.9,1%,1/16W,CHIA	CS04992FB07	5
Q_RES_0402LF-49.9,1%,1/16W,EMPA	CS04992FB07	2
Q_RES_0402LF-49.9K,1%,1/16W,CHA	CS34992FB05	2
Q_RES_0402LF-499,1%,1/16W,CHIPA	CS14992FB06	2
Q_RES_0402LF-5.1,5%,1/16W,CHIPA	CS-5102JB02	2
Q_RES_0402LF-5.36K,1%,1/16W,CHA	CS25362FB02	1
Q_RES_0402LF-5.49K,1%,1/16W,CHA	CS25492FB02	1
Q_RES_0402LF-56K,1%,1/16W,CHIPA	CS35602FB00	1
Q_RES_0402LF-60.4,1%,1/16W,CHIA	CS06042FB03	2
Q_RES_0402LF-60.4K,1%,1/16W,CHA	CS36042FB04	1
Q_RES_0402LF-665,1%,1/16W,CHIPA	CS16652FB00	1
Q_RES_0402LF-68.1,1%,1/16W,CHIA	CS06812FB03	1
Q_RES_0402LF-681K,1%,1/16W,CHIA	CS46812FB06	1
Q_RES_0402LF-75,1%,1/16W,CHIP,A	CS07502FB04	2
Q_RES_0402LF-750,1%,1/16W,CHIPA	CS17502FB03	8
Q_RES_0402LF-8.2K,5%,1/16W,CHIA	CS28202JB05	3
Q_RES_0402LF-8.2K,5%,1/16W,EMPA	CS28202JB05	3
Q_RES_0402LF-90.9,1%,1/16W,CHIA	CS09092FB15	1
Q_RES_0402LF-91K,1%,1/16W,CHIPA	CS39102FB06	1
Q_RES_0603LF-0,5%,1/10W,EMPTY,A	CS00003J910	3
RT9059GQW-RT9059GQW,SMLF,IC,ALA	AL009059000	2
SCHOTTKY_12-1N5819HW,SMLF,IC,BA	BC005819Z40	1
SCHOTTKY_12-SBA130Q,SMLF,EMPTYA	BCSBA130Z00	1
SCHOTTKY_AC-SS0530,SMLF,EMPTY,A	BCSS0530Z00	1
SCHOTTKY_AC-SS0530,SMLF,IC,BCSA	BCSS0530Z00	1
SCONN11_9192031111LF-SCONN11_9A	DFHS11FS009	2
SCONN13_502280130CV01-SCONN13_A	DFHD13MS080	1
SCONN16_ACASPI006P06-SCONN16_AA	DG016000006	1
SCONN3_21291035BR2-SCONN3_212-A	DFHD03MS251	1
SCONN3_212H9103GBR1-SCONN3_212A	DFHD03MS161	1
SCONN3_212H9103GBR1-SCONN3_212B	DFHD03MS161	1
SCONN67_NASA0S6730TS67-SCONN67A	DFHS75FR133	1
SN74LVC1G07DCKR-SN74LVC1G07DCKA	AL1G0007016	1
SN74LVC1G14DCKR_SMLF-IC,SN74LVA	AL001G14017	1
SW_PUSHBUTTON4P_12_G34_H2-SW4SA	DHPDTSAM601	3
TDR_3P_TH2-EMPTY,N_A	N_A	6
TPS3808G18DBVR-TPS3808G01DBVR,A	AL003808005	1
TP_TDR_4P_FTS_TH-TP_TDR_4P_DIPA	N_A	16

Total                                    1428
